# S9S_MB_2U (Grand Teton) — schematic netlist excerpt (pin names and nets, part order shuffled) for the footprints in the layout excerpt that follows; sources: Cadence DE-HDL packaged netlist, KiCad conversion of 03242023_DA0F0TMBIJ0_F0T_Motherboard_J_brd_V01_OCP.brd

R1255  Q_RES  1K 1% CHIP  pkg 0402LF  page 204 : A = PGPPA_AUX ; B = ESPI_ALERT1_N_LPC_RCIN_N
C2248  Q_CAP  1UF 25V 10% X6S  pkg C0402  page 225 : A = P3V3 ; B = GND

(kicad_pcb
	(version 20260206)
	(generator "pcbnew")
	(generator_version "10.0")
	(general
		(thickness 1.6)
		(legacy_teardrops no)
	)
	(paper "A4")
	(title_block
		(title "03242023_DA0F0TMBIJ0_F0T_Motherboard_J_brd_V01_OCP.brd")
		(comment 1 "Grand Teton / footprints 2622-2623 of 6105")
	)
	(layers
		(0 "F.Cu" signal "TOP")
		(4 "In1.Cu" signal "GND")
		(6 "In2.Cu" signal "IN1")
		(8 "In3.Cu" signal "GND1")
		(10 "In4.Cu" signal "IN2")
		(12 "In5.Cu" signal "GND2")
		(14 "In6.Cu" signal "IN3")
		(16 "In7.Cu" signal "GND3")
		(18 "In8.Cu" signal "VCC")
		(20 "In9.Cu" signal "VCC1")
		(22 "In10.Cu" signal "GND4")
		(24 "In11.Cu" signal "IN4")
		(26 "In12.Cu" signal "GND5")
		(28 "In13.Cu" signal "IN5")
		(30 "In14.Cu" signal "GND6")
		(32 "In15.Cu" signal "IN6")
		(34 "In16.Cu" signal "GND7")
		(2 "B.Cu" signal "BOTTOM")
		(9 "F.Adhes" user "F.Adhesive")
		(11 "B.Adhes" user "B.Adhesive")
		(13 "F.Paste" user "Package Geometry/Pastemask Top")
		(15 "B.Paste" user "Package Geometry/Pastemask Bottom")
		(5 "F.SilkS" user "Ref Des/Silkscreen Top")
		(7 "B.SilkS" user "Ref Des/Silkscreen Bottom")
		(1 "F.Mask" user "Board Geometry/Soldermask Top")
		(3 "B.Mask" user "Board Geometry/Soldermask Bottom")
		(17 "Dwgs.User" user "User.Drawings")
		(19 "Cmts.User" user "User.Comments")
		(21 "Eco1.User" user "User.Eco1")
		(23 "Eco2.User" user "User.Eco2")
		(25 "Edge.Cuts" user "Board Geometry/Outline")
		(27 "Margin" user)
		(31 "F.CrtYd" user "Package Geometry/Place Bound Top")
		(29 "B.CrtYd" user "Package Geometry/Place Bound Bottom")
		(35 "F.Fab" user "Ref Des/Assembly Top")
		(33 "B.Fab" user "Ref Des/Assembly Bottom")
	)
	(footprint ""
		(layer "F.Cu")
		(at 332.124812 -18.797016 -90)
		(property "Reference" "R1255"
			(at 0 0 270)
			(layer "F.SilkS")
			(hide yes)
			(effects
				(font
					(size 1.27 1.27)
				)
			)
		)
		(property "Value" ""
			(at 0 0 270)
			(layer "F.Fab")
			(effects
				(font
					(size 1.27 1.27)
				)
			)
		)
		(duplicate_pad_numbers_are_jumpers no)
		(fp_line
			(start -0.7874 0.4064)
			(end -0.7874 -0.4064)
			(stroke
				(width 0.1524)
				(type default)
			)
			(layer "F.SilkS")
		)
		(fp_line
			(start 0.7874 0.4064)
			(end -0.7874 0.4064)
			(stroke
				(width 0.1524)
				(type default)
			)
			(layer "F.SilkS")
		)
		(fp_line
			(start -0.7874 -0.4064)
			(end 0.7874 -0.4064)
			(stroke
				(width 0.1524)
				(type default)
			)
			(layer "F.SilkS")
		)
		(fp_line
			(start 0.7874 -0.4064)
			(end 0.7874 0.4064)
			(stroke
				(width 0.1524)
				(type default)
			)
			(layer "F.SilkS")
		)
		(fp_line
			(start -0.67945 0.3048)
			(end -0.67945 -0.305054)
			(stroke
				(width 0.1)
				(type default)
			)
			(layer "F.Fab")
		)
		(fp_line
			(start -0.12065 0.3048)
			(end -0.67945 0.3048)
			(stroke
				(width 0.1)
				(type default)
			)
			(layer "F.Fab")
		)
		(fp_line
			(start 0.120396 0.3048)
			(end 0.120396 0.2794)
			(stroke
				(width 0.1)
				(type default)
			)
			(layer "F.Fab")
		)
		(fp_line
			(start 0.67945 0.3048)
			(end 0.120396 0.3048)
			(stroke
				(width 0.1)
				(type default)
			)
			(layer "F.Fab")
		)
		(fp_line
			(start -0.12065 0.2794)
			(end -0.12065 0.3048)
			(stroke
				(width 0.1)
				(type default)
			)
			(layer "F.Fab")
		)
		(fp_line
			(start 0.120396 0.2794)
			(end -0.12065 0.2794)
			(stroke
				(width 0.1)
				(type default)
			)
			(layer "F.Fab")
		)
		(fp_line
			(start -0.12065 -0.2794)
			(end 0.12065 -0.2794)
			(stroke
				(width 0.1)
				(type default)
			)
			(layer "F.Fab")
		)
		(fp_line
			(start 0.12065 -0.2794)
			(end 0.12065 -0.3048)
			(stroke
				(width 0.1)
				(type default)
			)
			(layer "F.Fab")
		)
		(fp_line
			(start 0.12065 -0.3048)
			(end 0.67945 -0.3048)
			(stroke
				(width 0.1)
				(type default)
			)
			(layer "F.Fab")
		)
		(fp_line
			(start 0.67945 -0.3048)
			(end 0.67945 0.3048)
			(stroke
				(width 0.1)
				(type default)
			)
			(layer "F.Fab")
		)
		(fp_line
			(start -0.67945 -0.305054)
			(end -0.12065 -0.305054)
			(stroke
				(width 0.1)
				(type default)
			)
			(layer "F.Fab")
		)
		(fp_line
			(start -0.12065 -0.305054)
			(end -0.12065 -0.2794)
			(stroke
				(width 0.1)
				(type default)
			)
			(layer "F.Fab")
		)
		(pad "1" smd circle
			(at -0.40005 0 270)
			(size 0 0)
			(layers "F.Cu" "F.Mask" "F.Paste")
			(net "PGPPA_AUX")
		)
		(pad "2" smd circle
			(at 0.40005 0 270)
			(size 0 0)
			(layers "F.Cu" "F.Mask" "F.Paste")
			(net "ESPI_ALERT1_N_LPC_RCIN_N")
		)
	)
	(footprint ""
		(layer "F.Cu")
		(at 145.175224 -95.643446 -90)
		(property "Reference" "C2248"
			(at 0 0 270)
			(layer "F.SilkS")
			(hide yes)
			(effects
				(font
					(size 1.27 1.27)
				)
			)
		)
		(property "Value" ""
			(at 0 0 270)
			(layer "F.Fab")
			(effects
				(font
					(size 1.27 1.27)
				)
			)
		)
		(duplicate_pad_numbers_are_jumpers no)
		(fp_line
			(start -0.7874 0.4064)
			(end -0.7874 -0.4064)
			(stroke
				(width 0.1524)
				(type default)
			)
			(layer "F.SilkS")
		)
		(fp_line
			(start 0.7874 0.4064)
			(end -0.7874 0.4064)
			(stroke
				(width 0.1524)
				(type default)
			)
			(layer "F.SilkS")
		)
		(fp_line
			(start -0.7874 -0.4064)
			(end 0.7874 -0.4064)
			(stroke
				(width 0.1524)
				(type default)
			)
			(layer "F.SilkS")
		)
		(fp_line
			(start 0.7874 -0.4064)
			(end 0.7874 0.4064)
			(stroke
				(width 0.1524)
				(type default)
			)
			(layer "F.SilkS")
		)
		(fp_line
			(start -0.67945 0.3048)
			(end -0.67945 -0.305054)
			(stroke
				(width 0.1)
				(type default)
			)
			(layer "F.Fab")
		)
		(fp_line
			(start -0.12065 0.3048)
			(end -0.67945 0.3048)
			(stroke
				(width 0.1)
				(type default)
			)
			(layer "F.Fab")
		)
		(fp_line
			(start 0.120396 0.3048)
			(end 0.120396 0.2794)
			(stroke
				(width 0.1)
				(type default)
			)
			(layer "F.Fab")
		)
		(fp_line
			(start 0.67945 0.3048)
			(end 0.120396 0.3048)
			(stroke
				(width 0.1)
				(type default)
			)
			(layer "F.Fab")
		)
		(fp_line
			(start -0.12065 0.2794)
			(end -0.12065 0.3048)
			(stroke
				(width 0.1)
				(type default)
			)
			(layer "F.Fab")
		)
		(fp_line
			(start 0.120396 0.2794)
			(end -0.12065 0.2794)
			(stroke
				(width 0.1)
				(type default)
			)
			(layer "F.Fab")
		)
		(fp_line
			(start -0.12065 -0.2794)
			(end 0.12065 -0.2794)
			(stroke
				(width 0.1)
				(type default)
			)
			(layer "F.Fab")
		)
		(fp_line
			(start 0.12065 -0.2794)
			(end 0.12065 -0.3048)
			(stroke
				(width 0.1)
				(type default)
			)
			(layer "F.Fab")
		)
		(fp_line
			(start 0.12065 -0.3048)
			(end 0.67945 -0.3048)
			(stroke
				(width 0.1)
				(type default)
			)
			(layer "F.Fab")
		)
		(fp_line
			(start 0.67945 -0.3048)
			(end 0.67945 0.3048)
			(stroke
				(width 0.1)
				(type default)
			)
			(layer "F.Fab")
		)
		(fp_line
			(start -0.67945 -0.305054)
			(end -0.12065 -0.305054)
			(stroke
				(width 0.1)
				(type default)
			)
			(layer "F.Fab")
		)
		(fp_line
			(start -0.12065 -0.305054)
			(end -0.12065 -0.2794)
			(stroke
				(width 0.1)
				(type default)
			)
			(layer "F.Fab")
		)
		(pad "1" smd circle
			(at -0.40005 0 270)
			(size 0 0)
			(layers "F.Cu" "F.Mask" "F.Paste")
			(net "P3V3")
		)
		(pad "2" smd circle
			(at 0.40005 0 270)
			(size 0 0)
			(layers "F.Cu" "F.Mask" "F.Paste")
			(net "GND")
		)
	)
)
